# TIMECARD (Time Appliance Project (Time Card)) — schematic netlist excerpt (pin names and nets, part order shuffled) for the footprints in the layout excerpt that follows; sources: Cadence DE-HDL packaged netlist, KiCad conversion of R4006-B0001-02_R01.brd

R483  RESISTOR  1KOHM 1%  pkg SMC_0402R_H016  page 24 : \1\ = SG ; \2\ = MUX3_SEL
R223  RESISTOR  1KOHM 1%  pkg SMC_0402R_H016  page 11 : \1\ = PUDC ; \2\ = XP3R3V_FPGA

(kicad_pcb
	(version 20260206)
	(generator "pcbnew")
	(generator_version "10.0")
	(general
		(thickness 1.6)
		(legacy_teardrops no)
	)
	(paper "A4")
	(title_block
		(title "timecard-production-celestica-r4006 — R4006-B0001-02_R01.brd")
		(comment 1 "Time Appliance Project (Time Card) / footprints 754-755 of 1113")
	)
	(layers
		(0 "F.Cu" signal "TOP")
		(4 "In1.Cu" signal "L02_GND1")
		(6 "In2.Cu" signal "L03_SIG1")
		(8 "In3.Cu" signal "L04_GND2")
		(10 "In4.Cu" signal "L05_VCC1")
		(12 "In5.Cu" signal "L06_VCC2")
		(14 "In6.Cu" signal "L07_GND3")
		(16 "In7.Cu" signal "L08_SIG2")
		(18 "In8.Cu" signal "L09_GND4")
		(2 "B.Cu" signal "BOTTOM")
		(9 "F.Adhes" user "F.Adhesive")
		(11 "B.Adhes" user "B.Adhesive")
		(13 "F.Paste" user "Package Geometry/Pastemask Top")
		(15 "B.Paste" user "Package Geometry/Pastemask Bottom")
		(5 "F.SilkS" user "Ref Des/Silkscreen Top")
		(7 "B.SilkS" user "Ref Des/Silkscreen Bottom")
		(1 "F.Mask" user "Board Geometry/Soldermask Top")
		(3 "B.Mask" user "Board Geometry/Soldermask Bottom")
		(17 "Dwgs.User" user "User.Drawings")
		(19 "Cmts.User" user "User.Comments")
		(21 "Eco1.User" user "User.Eco1")
		(23 "Eco2.User" user "User.Eco2")
		(25 "Edge.Cuts" user "Board Geometry/Outline")
		(27 "Margin" user)
		(31 "F.CrtYd" user "Package Geometry/Place Bound Top")
		(29 "B.CrtYd" user "Package Geometry/Place Bound Bottom")
		(35 "F.Fab" user "Ref Des/Assembly Top")
		(33 "B.Fab" user "Ref Des/Assembly Bottom")
	)
	(footprint ""
		(layer "B.Cu")
		(at 119.761 -23.241 180)
		(property "Reference" "R483"
			(at 0 -1.18237 0)
			(unlocked yes)
			(layer "B.SilkS")
			(effects
				(font
					(size 0.7874 0.5842)
					(thickness 0.1524)
				)
				(justify mirror)
			)
		)
		(property "Value" "VAL*"
			(at -0.02032 2.13233 180)
			(unlocked yes)
			(layer "B.Fab")
			(hide yes)
			(effects
				(font
					(size 0.7874 0.5842)
					(thickness 0.1524)
				)
				(justify mirror)
			)
		)
		(property "Tolerance" "TOL*"
			(at -0.044704 3.05435 180)
			(unlocked yes)
			(layer "Cmts.User")
			(hide yes)
			(effects
				(font
					(size 0.7874 0.5842)
					(thickness 0.1524)
				)
				(justify mirror)
			)
		)
		(property "User Part Number" "PARTNUM*"
			(at -0.02032 4.024884 180)
			(unlocked yes)
			(layer "Cmts.User")
			(hide yes)
			(effects
				(font
					(size 0.7874 0.5842)
					(thickness 0.1524)
				)
				(justify mirror)
			)
		)
		(property "Device Type" "RESISTOR-G155-11001-01,1KOHM,1%"
			(at -0.008382 1.210564 180)
			(unlocked yes)
			(layer "B.Fab")
			(hide yes)
			(effects
				(font
					(size 0.7874 0.5842)
					(thickness 0.1524)
				)
				(justify mirror)
			)
		)
		(duplicate_pad_numbers_are_jumpers no)
		(fp_line
			(start 1.143 0.5588)
			(end -1.143 0.5588)
			(stroke
				(width 0.1)
				(type default)
			)
			(layer "B.SilkS")
		)
		(fp_line
			(start 1.143 -0.5588)
			(end 1.143 0.5588)
			(stroke
				(width 0.1)
				(type default)
			)
			(layer "B.SilkS")
		)
		(fp_line
			(start -1.143 0.5588)
			(end -1.143 -0.5588)
			(stroke
				(width 0.1)
				(type default)
			)
			(layer "B.SilkS")
		)
		(fp_line
			(start -1.143 -0.5588)
			(end 1.143 -0.5588)
			(stroke
				(width 0.1)
				(type default)
			)
			(layer "B.SilkS")
		)
		(fp_poly
			(pts
				(xy 1.143 0.5588) (xy -1.143 0.5588) (xy -1.143 -0.5588) (xy 1.143 -0.5588)
			)
			(stroke
				(width 0)
				(type default)
			)
			(fill no)
			(layer "B.CrtYd")
		)
		(fp_line
			(start 0.508 0.3048)
			(end -0.508 0.3048)
			(stroke
				(width 0.1)
				(type default)
			)
			(layer "B.Fab")
		)
		(fp_line
			(start 0.508 -0.3048)
			(end 0.508 0.3048)
			(stroke
				(width 0.1)
				(type default)
			)
			(layer "B.Fab")
		)
		(fp_line
			(start -0.508 0.3048)
			(end -0.508 -0.3048)
			(stroke
				(width 0.1)
				(type default)
			)
			(layer "B.Fab")
		)
		(fp_line
			(start -0.508 -0.3048)
			(end 0.508 -0.3048)
			(stroke
				(width 0.1)
				(type default)
			)
			(layer "B.Fab")
		)
		(pad "1" smd rect
			(at 0.5334 0)
			(size 0.7112 0.6096)
			(layers "B.Cu" "B.Mask" "B.Paste")
			(net "SG")
		)
		(pad "2" smd rect
			(at -0.5334 0)
			(size 0.7112 0.6096)
			(layers "B.Cu" "B.Mask" "B.Paste")
			(net "MUX3_SEL")
		)
		(zone
			(layer "B.Cu")
			(hatch none 0.5)
			(connect_pads
				(clearance 0)
			)
			(min_thickness 0.25)
			(keepout
				(tracks allowed)
				(vias not_allowed)
				(pads allowed)
				(copperpour not_allowed)
				(footprints allowed)
			)
			(placement
				(enabled no)
				(sheetname "")
			)
			(fill
				(thermal_gap 0.5)
				(thermal_bridge_width 0.5)
				(island_removal_mode 0)
			)
			(polygon
				(pts
					(xy 119.6848 -23.5458) (xy 119.6848 -22.9362) (xy 119.8372 -22.9362) (xy 119.8372 -23.5458)
				)
			)
		)
		(zone
			(layer "B.Cu")
			(hatch none 0.5)
			(connect_pads
				(clearance 0)
			)
			(min_thickness 0.25)
			(keepout
				(tracks not_allowed)
				(vias allowed)
				(pads allowed)
				(copperpour not_allowed)
				(footprints allowed)
			)
			(placement
				(enabled no)
				(sheetname "")
			)
			(fill
				(thermal_gap 0.5)
				(thermal_bridge_width 0.5)
				(island_removal_mode 0)
			)
			(polygon
				(pts
					(xy 119.6848 -23.5458) (xy 119.6848 -22.9362) (xy 119.8372 -22.9362) (xy 119.8372 -23.5458)
				)
			)
		)
	)
	(footprint ""
		(layer "B.Cu")
		(at 116.205 -61.976 -90)
		(property "Reference" "R223"
			(at -3.429 -0.08763 270)
			(unlocked yes)
			(layer "B.SilkS")
			(effects
				(font
					(size 0.7874 0.5842)
					(thickness 0.1524)
				)
				(justify mirror)
			)
		)
		(property "Value" "VAL*"
			(at -0.02032 2.13233 270)
			(unlocked yes)
			(layer "B.Fab")
			(hide yes)
			(effects
				(font
					(size 0.7874 0.5842)
					(thickness 0.1524)
				)
				(justify mirror)
			)
		)
		(property "Device Type" "RESISTOR-G155-11001-01,1KOHM,1%"
			(at -0.008382 1.210564 270)
			(unlocked yes)
			(layer "B.Fab")
			(hide yes)
			(effects
				(font
					(size 0.7874 0.5842)
					(thickness 0.1524)
				)
				(justify mirror)
			)
		)
		(property "User Part Number" "PARTNUM*"
			(at -0.02032 4.024884 270)
			(unlocked yes)
			(layer "Cmts.User")
			(hide yes)
			(effects
				(font
					(size 0.7874 0.5842)
					(thickness 0.1524)
				)
				(justify mirror)
			)
		)
		(property "Tolerance" "TOL*"
			(at -0.044704 3.05435 270)
			(unlocked yes)
			(layer "Cmts.User")
			(hide yes)
			(effects
				(font
					(size 0.7874 0.5842)
					(thickness 0.1524)
				)
				(justify mirror)
			)
		)
		(duplicate_pad_numbers_are_jumpers no)
		(fp_line
			(start -1.143 0.5588)
			(end -1.143 -0.5588)
			(stroke
				(width 0.1)
				(type default)
			)
			(layer "B.SilkS")
		)
		(fp_line
			(start 1.143 0.5588)
			(end -1.143 0.5588)
			(stroke
				(width 0.1)
				(type default)
			)
			(layer "B.SilkS")
		)
		(fp_line
			(start -1.143 -0.5588)
			(end 1.143 -0.5588)
			(stroke
				(width 0.1)
				(type default)
			)
			(layer "B.SilkS")
		)
		(fp_line
			(start 1.143 -0.5588)
			(end 1.143 0.5588)
			(stroke
				(width 0.1)
				(type default)
			)
			(layer "B.SilkS")
		)
		(fp_rect
			(start 1.143 -0.5588)
			(end -1.143 0.5588)
			(stroke
				(width 0)
				(type default)
			)
			(fill no)
			(layer "B.CrtYd")
		)
		(fp_line
			(start -0.508 0.3048)
			(end -0.508 -0.3048)
			(stroke
				(width 0.1)
				(type default)
			)
			(layer "B.Fab")
		)
		(fp_line
			(start 0.508 0.3048)
			(end -0.508 0.3048)
			(stroke
				(width 0.1)
				(type default)
			)
			(layer "B.Fab")
		)
		(fp_line
			(start -0.508 -0.3048)
			(end 0.508 -0.3048)
			(stroke
				(width 0.1)
				(type default)
			)
			(layer "B.Fab")
		)
		(fp_line
			(start 0.508 -0.3048)
			(end 0.508 0.3048)
			(stroke
				(width 0.1)
				(type default)
			)
			(layer "B.Fab")
		)
		(pad "1" smd rect
			(at 0.5334 0 90)
			(size 0.7112 0.6096)
			(layers "B.Cu" "B.Mask" "B.Paste")
			(net "PUDC")
		)
		(pad "2" smd rect
			(at -0.5334 0 90)
			(size 0.7112 0.6096)
			(layers "B.Cu" "B.Mask" "B.Paste")
			(net "XP3R3V_FPGA")
		)
		(zone
			(layer "B.Cu")
			(hatch none 0.5)
			(connect_pads
				(clearance 0)
			)
			(min_thickness 0.25)
			(keepout
				(tracks allowed)
				(vias not_allowed)
				(pads allowed)
				(copperpour not_allowed)
				(footprints allowed)
			)
			(placement
				(enabled no)
				(sheetname "")
			)
			(fill
				(thermal_gap 0.5)
				(thermal_bridge_width 0.5)
				(island_removal_mode 0)
			)
			(polygon
				(pts
					(xy 116.5098 -61.8998) (xy 116.5098 -62.0522) (xy 115.9002 -62.0522) (xy 115.9002 -61.8998)
				)
			)
		)
	)
)
